# BASEBOARD_FAB2 (Tioga Pass) — schematic netlist excerpt (pin names and nets, part order shuffled) for the footprints in the layout excerpt that follows; sources: Cadence DE-HDL packaged netlist, KiCad conversion of Wiwynn_Tioga_Pass_MB.brd

R6W25  RES  4.75K 1% CHIP  pkg 0402  page 247 : A = P3V3_STBY ; B = SMB_PMBUS_BMC_STBY_LVC3_SCL_R1
C5T8  CAP_A  47UF 4V 20% X5R  pkg 0603V  page 217 : A = PVDDQ_ABC ; B = GND
C5G57  CAP_A  22.0UF 4V 20% X6S  pkg 0603V  page 242 : A = PVDDQ_ABC ; B = GND

(kicad_pcb
	(version 20260206)
	(generator "pcbnew")
	(generator_version "10.0")
	(general
		(thickness 1.6)
		(legacy_teardrops no)
	)
	(paper "A4")
	(title_block
		(title "Wiwynn_Tioga_Pass_MB.brd")
		(comment 1 "Tioga Pass / footprints 4518-4520 of 4770")
	)
	(layers
		(0 "F.Cu" signal "TOP")
		(4 "In1.Cu" signal "L2GND")
		(6 "In2.Cu" signal "L3")
		(8 "In3.Cu" signal "L4GND")
		(10 "In4.Cu" signal "L5")
		(12 "In5.Cu" signal "L6GND")
		(14 "In6.Cu" signal "L7VCC")
		(16 "In7.Cu" signal "L8VCC")
		(18 "In8.Cu" signal "L9GND")
		(20 "In9.Cu" signal "L10")
		(22 "In10.Cu" signal "L11GND")
		(24 "In11.Cu" signal "L12")
		(26 "In12.Cu" signal "L13GND")
		(2 "B.Cu" signal "BOTTOM")
		(9 "F.Adhes" user "F.Adhesive")
		(11 "B.Adhes" user "B.Adhesive")
		(13 "F.Paste" user "Package Geometry/Pastemask Top")
		(15 "B.Paste" user "Package Geometry/Pastemask Bottom")
		(5 "F.SilkS" user "Ref Des/Silkscreen Top")
		(7 "B.SilkS" user "Ref Des/Silkscreen Bottom")
		(1 "F.Mask" user "Board Geometry/Soldermask Top")
		(3 "B.Mask" user "Board Geometry/Soldermask Bottom")
		(17 "Dwgs.User" user "User.Drawings")
		(19 "Cmts.User" user "User.Comments")
		(21 "Eco1.User" user "User.Eco1")
		(23 "Eco2.User" user "User.Eco2")
		(25 "Edge.Cuts" user "Board Geometry/Outline")
		(27 "Margin" user)
		(31 "F.CrtYd" user "Package Geometry/Place Bound Top")
		(29 "B.CrtYd" user "Package Geometry/Place Bound Bottom")
		(35 "F.Fab" user "Ref Des/Assembly Top")
		(33 "B.Fab" user "Ref Des/Assembly Bottom")
	)
	(footprint ""
		(layer "B.Cu")
		(at 401.066 -104.0765 180)
		(property "Reference" "R6W25"
			(at 0.8382 -0.67818 180)
			(unlocked yes)
			(layer "B.SilkS")
			(effects
				(font
					(size 0.4064 0.254)
					(thickness 0.1524)
				)
				(justify left mirror)
			)
		)
		(property "Value" ""
			(at 0 0 0)
			(layer "B.Fab")
			(effects
				(font
					(size 1.27 1.27)
				)
				(justify mirror)
			)
		)
		(duplicate_pad_numbers_are_jumpers no)
		(fp_poly
			(pts
				(xy 0.2794 -0.1016) (xy -0.2794 -0.1016) (xy -0.2794 0.9906) (xy 0.2794 0.9906)
			)
			(stroke
				(width 0)
				(type default)
			)
			(fill no)
			(layer "B.CrtYd")
		)
		(fp_line
			(start 0.2794 0.9906)
			(end -0.2794 0.9906)
			(stroke
				(width 0.1)
				(type default)
			)
			(layer "B.Fab")
		)
		(fp_line
			(start 0.2794 -0.1016)
			(end 0.2794 0.9906)
			(stroke
				(width 0.1)
				(type default)
			)
			(layer "B.Fab")
		)
		(fp_line
			(start -0.2794 0.9906)
			(end -0.2794 -0.1016)
			(stroke
				(width 0.1)
				(type default)
			)
			(layer "B.Fab")
		)
		(fp_line
			(start -0.2794 -0.1016)
			(end 0.2794 -0.1016)
			(stroke
				(width 0.1)
				(type default)
			)
			(layer "B.Fab")
		)
		(pad "1" smd rect
			(at 0 0)
			(size 0.508 0.508)
			(layers "B.Cu" "B.Mask" "B.Paste")
			(net "P3V3_STBY")
		)
		(pad "2" smd rect
			(at 0 0.889)
			(size 0.508 0.508)
			(layers "B.Cu" "B.Mask" "B.Paste")
			(net "SMB_PMBUS_BMC_STBY_LVC3_SCL_R1")
		)
		(zone
			(layer "B.Cu")
			(hatch none 0.5)
			(connect_pads
				(clearance 0)
			)
			(min_thickness 0.25)
			(keepout
				(tracks not_allowed)
				(vias allowed)
				(pads allowed)
				(copperpour not_allowed)
				(footprints allowed)
			)
			(placement
				(enabled no)
				(sheetname "")
			)
			(fill
				(thermal_gap 0.5)
				(thermal_bridge_width 0.5)
				(island_removal_mode 0)
			)
			(polygon
				(pts
					(xy 400.812 -104.7115) (xy 401.32 -104.7115) (xy 401.32 -104.3305) (xy 400.812 -104.3305)
				)
			)
		)
		(zone
			(layer "B.Cu")
			(hatch none 0.5)
			(connect_pads
				(clearance 0)
			)
			(min_thickness 0.25)
			(keepout
				(tracks allowed)
				(vias not_allowed)
				(pads allowed)
				(copperpour not_allowed)
				(footprints allowed)
			)
			(placement
				(enabled no)
				(sheetname "")
			)
			(fill
				(thermal_gap 0.5)
				(thermal_bridge_width 0.5)
				(island_removal_mode 0)
			)
			(polygon
				(pts
					(xy 400.812 -104.3305) (xy 401.32 -104.3305) (xy 401.32 -104.7115) (xy 400.812 -104.7115)
				)
			)
		)
	)
	(footprint ""
		(layer "B.Cu")
		(at 266.397232 -17.7546 90)
		(property "Reference" "C5T8"
			(at -1.848866 0.752348 90)
			(unlocked yes)
			(layer "B.SilkS")
			(effects
				(font
					(size 1.27 0.9652)
					(thickness 0.1524)
				)
				(justify mirror)
			)
		)
		(property "Value" ""
			(at 0 0 90)
			(layer "B.Fab")
			(effects
				(font
					(size 1.27 1.27)
				)
				(justify mirror)
			)
		)
		(duplicate_pad_numbers_are_jumpers no)
		(fp_rect
			(start 0.500126 1.598422)
			(end -0.500126 -0.201422)
			(stroke
				(width 0)
				(type default)
			)
			(fill no)
			(layer "B.CrtYd")
		)
		(fp_line
			(start 0.500126 -0.201422)
			(end -0.500126 -0.201422)
			(stroke
				(width 0.1)
				(type default)
			)
			(layer "B.Fab")
		)
		(fp_line
			(start -0.500126 -0.201422)
			(end -0.500126 1.598422)
			(stroke
				(width 0.1)
				(type default)
			)
			(layer "B.Fab")
		)
		(fp_line
			(start 0.500126 1.598422)
			(end 0.500126 -0.201422)
			(stroke
				(width 0.1)
				(type default)
			)
			(layer "B.Fab")
		)
		(fp_line
			(start -0.500126 1.598422)
			(end 0.500126 1.598422)
			(stroke
				(width 0.1)
				(type default)
			)
			(layer "B.Fab")
		)
		(pad "1" smd rect
			(at 0 0)
			(size 0.889 0.9906)
			(layers "B.Cu" "B.Mask" "B.Paste")
			(net "PVDDQ_ABC")
		)
		(pad "2" smd rect
			(at 0 1.397)
			(size 0.889 0.9906)
			(layers "B.Cu" "B.Mask" "B.Paste")
			(net "GND")
		)
		(zone
			(layer "B.Cu")
			(hatch none 0.5)
			(connect_pads
				(clearance 0)
			)
			(min_thickness 0.25)
			(keepout
				(tracks allowed)
				(vias not_allowed)
				(pads allowed)
				(copperpour not_allowed)
				(footprints allowed)
			)
			(placement
				(enabled no)
				(sheetname "")
			)
			(fill
				(thermal_gap 0.5)
				(thermal_bridge_width 0.5)
				(island_removal_mode 0)
			)
			(polygon
				(pts
					(xy 267.349732 -18.2499) (xy 266.841732 -18.2499) (xy 266.841732 -17.2593) (xy 267.349732 -17.2593)
				)
			)
		)
		(zone
			(layer "B.Cu")
			(hatch none 0.5)
			(connect_pads
				(clearance 0)
			)
			(min_thickness 0.25)
			(keepout
				(tracks not_allowed)
				(vias allowed)
				(pads allowed)
				(copperpour not_allowed)
				(footprints allowed)
			)
			(placement
				(enabled no)
				(sheetname "")
			)
			(fill
				(thermal_gap 0.5)
				(thermal_bridge_width 0.5)
				(island_removal_mode 0)
			)
			(polygon
				(pts
					(xy 267.349732 -18.2499) (xy 266.841732 -18.2499) (xy 266.841732 -17.2593) (xy 267.349732 -17.2593)
				)
			)
		)
	)
	(footprint ""
		(layer "B.Cu")
		(at 269.559532 -3.3528 90)
		(property "Reference" "C5G57"
			(at -1.14681 0.76708 180)
			(unlocked yes)
			(layer "B.SilkS")
			(effects
				(font
					(size 0.7874 0.5842)
					(thickness 0.1524)
				)
				(justify mirror)
			)
		)
		(property "Value" ""
			(at 0 0 90)
			(layer "B.Fab")
			(effects
				(font
					(size 1.27 1.27)
				)
				(justify mirror)
			)
		)
		(duplicate_pad_numbers_are_jumpers no)
		(fp_rect
			(start -0.4953 -0.2032)
			(end 0.4953 1.6002)
			(stroke
				(width 0)
				(type default)
			)
			(fill no)
			(layer "B.CrtYd")
		)
		(fp_line
			(start 0.4953 -0.2032)
			(end -0.4953 -0.2032)
			(stroke
				(width 0.1)
				(type default)
			)
			(layer "B.Fab")
		)
		(fp_line
			(start -0.4953 -0.2032)
			(end -0.4953 1.6002)
			(stroke
				(width 0.1)
				(type default)
			)
			(layer "B.Fab")
		)
		(fp_line
			(start 0.4953 1.6002)
			(end 0.4953 -0.2032)
			(stroke
				(width 0.1)
				(type default)
			)
			(layer "B.Fab")
		)
		(fp_line
			(start -0.4953 1.6002)
			(end 0.4953 1.6002)
			(stroke
				(width 0.1)
				(type default)
			)
			(layer "B.Fab")
		)
		(pad "1" smd rect
			(at 0 0 270)
			(size 0.762 0.889)
			(layers "B.Cu" "B.Mask" "B.Paste")
			(net "PVDDQ_ABC")
		)
		(pad "2" smd rect
			(at 0 1.397 270)
			(size 0.762 0.889)
			(layers "B.Cu" "B.Mask" "B.Paste")
			(net "GND")
		)
		(zone
			(layer "B.Cu")
			(hatch none 0.5)
			(connect_pads
				(clearance 0)
			)
			(min_thickness 0.25)
			(keepout
				(tracks not_allowed)
				(vias allowed)
				(pads allowed)
				(copperpour not_allowed)
				(footprints allowed)
			)
			(placement
				(enabled no)
				(sheetname "")
			)
			(fill
				(thermal_gap 0.5)
				(thermal_bridge_width 0.5)
				(island_removal_mode 0)
			)
			(polygon
				(pts
					(xy 270.004032 -2.9718) (xy 270.512032 -2.9718) (xy 270.512032 -3.7338) (xy 270.004032 -3.7338)
				)
			)
		)
	)
)
